(kicad_pcb
	(version 20260206)
	(generator "pcbnew")
	(generator_version "10.0")
	(general
		(thickness 1.6)
		(legacy_teardrops no)
	)
	(paper "A4")
	(title_block
		(title "fcb — 12433-1M.1206WZS1330.brd")
		(comment 1 "Open Vault / Knox (Wiwynn) / footprints 223-229 of 495")
	)
	(layers
		(0 "F.Cu" signal "TOP")
		(4 "In1.Cu" signal "L2GND")
		(6 "In2.Cu" signal "L3VCC")
		(2 "B.Cu" signal "BOTTOM")
		(9 "F.Adhes" user "F.Adhesive")
		(11 "B.Adhes" user "B.Adhesive")
		(13 "F.Paste" user "Package Geometry/Pastemask Top")
		(15 "B.Paste" user "Package Geometry/Pastemask Bottom")
		(5 "F.SilkS" user "Ref Des/Silkscreen Top")
		(7 "B.SilkS" user "Ref Des/Silkscreen Bottom")
		(1 "F.Mask" user "Board Geometry/Soldermask Top")
		(3 "B.Mask" user "Board Geometry/Soldermask Bottom")
		(17 "Dwgs.User" user "User.Drawings")
		(19 "Cmts.User" user "User.Comments")
		(21 "Eco1.User" user "User.Eco1")
		(23 "Eco2.User" user "User.Eco2")
		(25 "Edge.Cuts" user "Board Geometry/Outline")
		(27 "Margin" user)
		(31 "F.CrtYd" user "Package Geometry/Place Bound Top")
		(29 "B.CrtYd" user "Package Geometry/Place Bound Bottom")
		(35 "F.Fab" user "Ref Des/Assembly Top")
		(33 "B.Fab" user "Ref Des/Assembly Bottom")
	)
	(footprint ""
		(layer "F.Cu")
		(at 5.4864 -449.4784 -90)
		(property "Reference" "R104"
			(at 0 0 270)
			(layer "F.SilkS")
			(hide yes)
			(effects
				(font
					(size 1.27 1.27)
				)
			)
		)
		(property "Value" "10KR2F-2-GP"
			(at 0.064008 -3.993896 270)
			(unlocked yes)
			(layer "F.Fab")
			(hide yes)
			(effects
				(font
					(size 1.016 1.016)
					(thickness 0.1524)
				)
			)
		)
		(property "Device Type" "R402H16"
			(at 0.064008 -5.517896 270)
			(unlocked yes)
			(layer "F.Fab")
			(hide yes)
			(effects
				(font
					(size 1.016 1.016)
					(thickness 0.1524)
				)
			)
		)
		(duplicate_pad_numbers_are_jumpers no)
		(fp_line
			(start -0.508 -0.9398)
			(end -0.508 0.9398)
			(stroke
				(width 0.1524)
				(type default)
			)
			(layer "F.SilkS")
		)
		(fp_line
			(start 0.508 -0.9398)
			(end -0.508 -0.9398)
			(stroke
				(width 0.1524)
				(type default)
			)
			(layer "F.SilkS")
		)
		(fp_rect
			(start -0.508 0.9398)
			(end 0.508 -0.9398)
			(stroke
				(width 0)
				(type default)
			)
			(fill no)
			(layer "F.CrtYd")
		)
		(fp_rect
			(start -0.508 0.9398)
			(end 0.508 -0.9398)
			(stroke
				(width 0)
				(type default)
			)
			(fill no)
			(layer "F.Fab")
		)
		(pad "1" smd custom
			(at 0 -0.4445 270)
			(size 0.1397 0.1397)
			(layers "F.Cu" "F.Mask" "F.Paste")
			(net "FANIN_1")
			(options
				(clearance outline)
				(anchor circle)
			)
			(primitives
				(gr_poly
					(pts
						(arc
							(start -0.1778 -0.2794)
							(mid -0.249642 -0.249642)
							(end -0.2794 -0.1778)
						)
						(arc
							(start -0.2794 0.1778)
							(mid -0.249642 0.249642)
							(end -0.1778 0.2794)
						)
						(arc
							(start 0.1778 0.2794)
							(mid 0.249642 0.249642)
							(end 0.2794 0.1778)
						)
						(arc
							(start 0.2794 -0.1778)
							(mid 0.249642 -0.249642)
							(end 0.1778 -0.2794)
						)
					)
					(width 0)
					(fill yes)
				)
			)
		)
		(pad "2" smd custom
			(at 0 0.4445 270)
			(size 0.1397 0.1397)
			(layers "F.Cu" "F.Mask" "F.Paste")
			(net "GND")
			(options
				(clearance outline)
				(anchor circle)
			)
			(primitives
				(gr_poly
					(pts
						(arc
							(start -0.1778 -0.2794)
							(mid -0.249642 -0.249642)
							(end -0.2794 -0.1778)
						)
						(arc
							(start -0.2794 0.1778)
							(mid -0.249642 0.249642)
							(end -0.1778 0.2794)
						)
						(arc
							(start 0.1778 0.2794)
							(mid 0.249642 0.249642)
							(end 0.2794 0.1778)
						)
						(arc
							(start 0.2794 -0.1778)
							(mid 0.249642 -0.249642)
							(end 0.1778 -0.2794)
						)
					)
					(width 0)
					(fill yes)
				)
			)
		)
	)
	(footprint ""
		(layer "F.Cu")
		(at 37.973 -147.4216 180)
		(property "Reference" "PC94"
			(at 0 0 180)
			(layer "F.SilkS")
			(hide yes)
			(effects
				(font
					(size 1.27 1.27)
				)
			)
		)
		(property "Value" "SC220P50V2KX-3GP"
			(at 1.1811 -2.7051 180)
			(unlocked yes)
			(layer "F.Fab")
			(hide yes)
			(effects
				(font
					(size 1.016 1.016)
					(thickness 0.1524)
				)
			)
		)
		(property "Device Type" "C402H22"
			(at 1.1811 -4.2291 180)
			(unlocked yes)
			(layer "F.Fab")
			(hide yes)
			(effects
				(font
					(size 1.016 1.016)
					(thickness 0.1524)
				)
			)
		)
		(duplicate_pad_numbers_are_jumpers no)
		(fp_rect
			(start -0.4318 0.9525)
			(end 0.4318 -0.9525)
			(stroke
				(width 0)
				(type default)
			)
			(fill no)
			(layer "F.CrtYd")
		)
		(fp_rect
			(start -0.4318 0.9525)
			(end 0.4318 -0.9525)
			(stroke
				(width 0)
				(type default)
			)
			(fill no)
			(layer "F.Fab")
		)
		(pad "1" smd custom
			(at 0 -0.4445 180)
			(size 0.1524 0.1524)
			(layers "F.Cu" "F.Mask" "F.Paste")
			(net "P12VL_2490_VREF")
			(options
				(clearance outline)
				(anchor circle)
			)
			(primitives
				(gr_poly
					(pts
						(arc
							(start 0.3048 -0.2032)
							(mid 0.275042 -0.275042)
							(end 0.2032 -0.3048)
						)
						(arc
							(start -0.2032 -0.3048)
							(mid -0.275042 -0.275042)
							(end -0.3048 -0.2032)
						)
						(arc
							(start -0.3048 0.2032)
							(mid -0.275042 0.275042)
							(end -0.2032 0.3048)
						)
						(arc
							(start 0.2032 0.3048)
							(mid 0.275042 0.275042)
							(end 0.3048 0.2032)
						)
					)
					(width 0)
					(fill yes)
				)
			)
		)
		(pad "2" smd custom
			(at 0 0.4445 180)
			(size 0.1524 0.1524)
			(layers "F.Cu" "F.Mask" "F.Paste")
			(net "GND")
			(options
				(clearance outline)
				(anchor circle)
			)
			(primitives
				(gr_poly
					(pts
						(arc
							(start 0.3048 -0.2032)
							(mid 0.275042 -0.275042)
							(end 0.2032 -0.3048)
						)
						(arc
							(start -0.2032 -0.3048)
							(mid -0.275042 -0.275042)
							(end -0.3048 -0.2032)
						)
						(arc
							(start -0.3048 0.2032)
							(mid -0.275042 0.275042)
							(end -0.2032 0.3048)
						)
						(arc
							(start 0.2032 0.3048)
							(mid 0.275042 0.275042)
							(end 0.3048 0.2032)
						)
					)
					(width 0)
					(fill yes)
				)
			)
		)
	)
	(footprint ""
		(layer "F.Cu")
		(at 39.243 -149.098 -90)
		(property "Reference" "PR108"
			(at 0 0 270)
			(layer "F.SilkS")
			(hide yes)
			(effects
				(font
					(size 1.27 1.27)
				)
			)
		)
		(property "Value" "6K81R2F-1-GP"
			(at 0.064008 -3.993896 270)
			(unlocked yes)
			(layer "F.Fab")
			(hide yes)
			(effects
				(font
					(size 1.016 1.016)
					(thickness 0.1524)
				)
			)
		)
		(property "Device Type" "R402H16"
			(at 0.064008 -5.517896 270)
			(unlocked yes)
			(layer "F.Fab")
			(hide yes)
			(effects
				(font
					(size 1.016 1.016)
					(thickness 0.1524)
				)
			)
		)
		(duplicate_pad_numbers_are_jumpers no)
		(fp_line
			(start -0.508 -0.9398)
			(end -0.508 0.9398)
			(stroke
				(width 0.1524)
				(type default)
			)
			(layer "F.SilkS")
		)
		(fp_line
			(start 0.508 -0.9398)
			(end -0.508 -0.9398)
			(stroke
				(width 0.1524)
				(type default)
			)
			(layer "F.SilkS")
		)
		(fp_rect
			(start -0.508 0.9398)
			(end 0.508 -0.9398)
			(stroke
				(width 0)
				(type default)
			)
			(fill no)
			(layer "F.CrtYd")
		)
		(fp_rect
			(start -0.508 0.9398)
			(end 0.508 -0.9398)
			(stroke
				(width 0)
				(type default)
			)
			(fill no)
			(layer "F.Fab")
		)
		(pad "1" smd custom
			(at 0 -0.4445 270)
			(size 0.1397 0.1397)
			(layers "F.Cu" "F.Mask" "F.Paste")
			(net "P12V")
			(options
				(clearance outline)
				(anchor circle)
			)
			(primitives
				(gr_poly
					(pts
						(arc
							(start -0.1778 -0.2794)
							(mid -0.249642 -0.249642)
							(end -0.2794 -0.1778)
						)
						(arc
							(start -0.2794 0.1778)
							(mid -0.249642 0.249642)
							(end -0.1778 0.2794)
						)
						(arc
							(start 0.1778 0.2794)
							(mid 0.249642 0.249642)
							(end 0.2794 0.1778)
						)
						(arc
							(start 0.2794 -0.1778)
							(mid 0.249642 -0.249642)
							(end 0.1778 -0.2794)
						)
					)
					(width 0)
					(fill yes)
				)
			)
		)
		(pad "2" smd custom
			(at 0 0.4445 270)
			(size 0.1397 0.1397)
			(layers "F.Cu" "F.Mask" "F.Paste")
			(net "P12VU_2490_EN_1")
			(options
				(clearance outline)
				(anchor circle)
			)
			(primitives
				(gr_poly
					(pts
						(arc
							(start -0.1778 -0.2794)
							(mid -0.249642 -0.249642)
							(end -0.2794 -0.1778)
						)
						(arc
							(start -0.2794 0.1778)
							(mid -0.249642 0.249642)
							(end -0.1778 0.2794)
						)
						(arc
							(start 0.1778 0.2794)
							(mid 0.249642 0.249642)
							(end 0.2794 0.1778)
						)
						(arc
							(start 0.2794 -0.1778)
							(mid 0.249642 -0.249642)
							(end 0.1778 -0.2794)
						)
					)
					(width 0)
					(fill yes)
				)
			)
		)
	)
	(footprint ""
		(layer "F.Cu")
		(at 7.239 -454.1012 -90)
		(property "Reference" "C45"
			(at 0 0 270)
			(layer "F.SilkS")
			(hide yes)
			(effects
				(font
					(size 1.27 1.27)
				)
			)
		)
		(property "Value" "SCD1U16V2KX-3GP"
			(at 1.1811 -2.7051 270)
			(unlocked yes)
			(layer "F.Fab")
			(hide yes)
			(effects
				(font
					(size 1.016 1.016)
					(thickness 0.1524)
				)
			)
		)
		(property "Device Type" "C402H22"
			(at 1.1811 -4.2291 270)
			(unlocked yes)
			(layer "F.Fab")
			(hide yes)
			(effects
				(font
					(size 1.016 1.016)
					(thickness 0.1524)
				)
			)
		)
		(duplicate_pad_numbers_are_jumpers no)
		(fp_rect
			(start -0.4318 0.9525)
			(end 0.4318 -0.9525)
			(stroke
				(width 0)
				(type default)
			)
			(fill no)
			(layer "F.CrtYd")
		)
		(fp_rect
			(start -0.4318 0.9525)
			(end 0.4318 -0.9525)
			(stroke
				(width 0)
				(type default)
			)
			(fill no)
			(layer "F.Fab")
		)
		(pad "1" smd custom
			(at 0 -0.4445 270)
			(size 0.1524 0.1524)
			(layers "F.Cu" "F.Mask" "F.Paste")
			(net "FAN_TACH1")
			(options
				(clearance outline)
				(anchor circle)
			)
			(primitives
				(gr_poly
					(pts
						(arc
							(start 0.3048 -0.2032)
							(mid 0.275042 -0.275042)
							(end 0.2032 -0.3048)
						)
						(arc
							(start -0.2032 -0.3048)
							(mid -0.275042 -0.275042)
							(end -0.3048 -0.2032)
						)
						(arc
							(start -0.3048 0.2032)
							(mid -0.275042 0.275042)
							(end -0.2032 0.3048)
						)
						(arc
							(start 0.2032 0.3048)
							(mid 0.275042 0.275042)
							(end 0.3048 0.2032)
						)
					)
					(width 0)
					(fill yes)
				)
			)
		)
		(pad "2" smd custom
			(at 0 0.4445 270)
			(size 0.1524 0.1524)
			(layers "F.Cu" "F.Mask" "F.Paste")
			(net "GND")
			(options
				(clearance outline)
				(anchor circle)
			)
			(primitives
				(gr_poly
					(pts
						(arc
							(start 0.3048 -0.2032)
							(mid 0.275042 -0.275042)
							(end 0.2032 -0.3048)
						)
						(arc
							(start -0.2032 -0.3048)
							(mid -0.275042 -0.275042)
							(end -0.3048 -0.2032)
						)
						(arc
							(start -0.3048 0.2032)
							(mid -0.275042 0.275042)
							(end -0.2032 0.3048)
						)
						(arc
							(start 0.2032 0.3048)
							(mid 0.275042 0.275042)
							(end 0.3048 0.2032)
						)
					)
					(width 0)
					(fill yes)
				)
			)
		)
	)
	(footprint ""
		(layer "F.Cu")
		(at 17.271492 -13.919962 180)
		(property "Reference" "R69"
			(at 0 0 180)
			(layer "F.SilkS")
			(hide yes)
			(effects
				(font
					(size 1.27 1.27)
				)
			)
		)
		(property "Value" "4K7R2F-GP"
			(at 0.064008 -3.993896 180)
			(unlocked yes)
			(layer "F.Fab")
			(hide yes)
			(effects
				(font
					(size 1.016 1.016)
					(thickness 0.1524)
				)
			)
		)
		(property "Device Type" "R402H16"
			(at 0.064008 -5.517896 180)
			(unlocked yes)
			(layer "F.Fab")
			(hide yes)
			(effects
				(font
					(size 1.016 1.016)
					(thickness 0.1524)
				)
			)
		)
		(duplicate_pad_numbers_are_jumpers no)
		(fp_line
			(start 0.508 -0.9398)
			(end -0.508 -0.9398)
			(stroke
				(width 0.1524)
				(type default)
			)
			(layer "F.SilkS")
		)
		(fp_line
			(start -0.508 -0.9398)
			(end -0.508 0.9398)
			(stroke
				(width 0.1524)
				(type default)
			)
			(layer "F.SilkS")
		)
		(fp_rect
			(start -0.508 0.9398)
			(end 0.508 -0.9398)
			(stroke
				(width 0)
				(type default)
			)
			(fill no)
			(layer "F.CrtYd")
		)
		(fp_rect
			(start -0.508 0.9398)
			(end 0.508 -0.9398)
			(stroke
				(width 0)
				(type default)
			)
			(fill no)
			(layer "F.Fab")
		)
		(pad "1" smd custom
			(at 0 -0.4445 180)
			(size 0.1397 0.1397)
			(layers "F.Cu" "F.Mask" "F.Paste")
			(net "P12V")
			(options
				(clearance outline)
				(anchor circle)
			)
			(primitives
				(gr_poly
					(pts
						(arc
							(start -0.1778 -0.2794)
							(mid -0.249642 -0.249642)
							(end -0.2794 -0.1778)
						)
						(arc
							(start -0.2794 0.1778)
							(mid -0.249642 0.249642)
							(end -0.1778 0.2794)
						)
						(arc
							(start 0.1778 0.2794)
							(mid 0.249642 0.249642)
							(end 0.2794 0.1778)
						)
						(arc
							(start 0.2794 -0.1778)
							(mid 0.249642 -0.249642)
							(end 0.1778 -0.2794)
						)
					)
					(width 0)
					(fill yes)
				)
			)
		)
		(pad "2" smd custom
			(at 0 0.4445 180)
			(size 0.1397 0.1397)
			(layers "F.Cu" "F.Mask" "F.Paste")
			(net "FAN_TACH11")
			(options
				(clearance outline)
				(anchor circle)
			)
			(primitives
				(gr_poly
					(pts
						(arc
							(start -0.1778 -0.2794)
							(mid -0.249642 -0.249642)
							(end -0.2794 -0.1778)
						)
						(arc
							(start -0.2794 0.1778)
							(mid -0.249642 0.249642)
							(end -0.1778 0.2794)
						)
						(arc
							(start 0.1778 0.2794)
							(mid 0.249642 0.249642)
							(end 0.2794 0.1778)
						)
						(arc
							(start 0.2794 -0.1778)
							(mid 0.249642 -0.249642)
							(end 0.1778 -0.2794)
						)
					)
					(width 0)
					(fill yes)
				)
			)
		)
	)
	(footprint ""
		(layer "F.Cu")
		(at 34.798 -381 180)
		(property "Reference" "PR24"
			(at 0 0 180)
			(layer "F.SilkS")
			(hide yes)
			(effects
				(font
					(size 1.27 1.27)
				)
			)
		)
		(property "Value" "10R2F-L-GP"
			(at 0.064008 -3.993896 180)
			(unlocked yes)
			(layer "F.Fab")
			(hide yes)
			(effects
				(font
					(size 1.016 1.016)
					(thickness 0.1524)
				)
			)
		)
		(property "Device Type" "R402H14"
			(at 0.064008 -5.517896 180)
			(unlocked yes)
			(layer "F.Fab")
			(hide yes)
			(effects
				(font
					(size 1.016 1.016)
					(thickness 0.1524)
				)
			)
		)
		(duplicate_pad_numbers_are_jumpers no)
		(fp_line
			(start 0.508 -0.9398)
			(end -0.508 -0.9398)
			(stroke
				(width 0.1524)
				(type default)
			)
			(layer "F.SilkS")
		)
		(fp_line
			(start -0.508 -0.9398)
			(end -0.508 0.9398)
			(stroke
				(width 0.1524)
				(type default)
			)
			(layer "F.SilkS")
		)
		(fp_rect
			(start -0.508 0.9398)
			(end 0.508 -0.9398)
			(stroke
				(width 0)
				(type default)
			)
			(fill no)
			(layer "F.CrtYd")
		)
		(fp_rect
			(start -0.508 0.9398)
			(end 0.508 -0.9398)
			(stroke
				(width 0)
				(type default)
			)
			(fill no)
			(layer "F.Fab")
		)
		(pad "1" smd custom
			(at 0 -0.4445 180)
			(size 0.1397 0.1397)
			(layers "F.Cu" "F.Mask" "F.Paste")
			(net "ADM1276_SENSE-")
			(options
				(clearance outline)
				(anchor circle)
			)
			(primitives
				(gr_poly
					(pts
						(arc
							(start -0.1778 -0.2794)
							(mid -0.249642 -0.249642)
							(end -0.2794 -0.1778)
						)
						(arc
							(start -0.2794 0.1778)
							(mid -0.249642 0.249642)
							(end -0.1778 0.2794)
						)
						(arc
							(start 0.1778 0.2794)
							(mid 0.249642 0.249642)
							(end 0.2794 0.1778)
						)
						(arc
							(start 0.2794 -0.1778)
							(mid 0.249642 -0.249642)
							(end 0.1778 -0.2794)
						)
					)
					(width 0)
					(fill yes)
				)
			)
		)
		(pad "2" smd custom
			(at 0 0.4445 180)
			(size 0.1397 0.1397)
			(layers "F.Cu" "F.Mask" "F.Paste")
			(net "SENSE-_R4")
			(options
				(clearance outline)
				(anchor circle)
			)
			(primitives
				(gr_poly
					(pts
						(arc
							(start -0.1778 -0.2794)
							(mid -0.249642 -0.249642)
							(end -0.2794 -0.1778)
						)
						(arc
							(start -0.2794 0.1778)
							(mid -0.249642 0.249642)
							(end -0.1778 0.2794)
						)
						(arc
							(start 0.1778 0.2794)
							(mid 0.249642 0.249642)
							(end 0.2794 0.1778)
						)
						(arc
							(start 0.2794 -0.1778)
							(mid 0.249642 -0.249642)
							(end 0.1778 -0.2794)
						)
					)
					(width 0)
					(fill yes)
				)
			)
		)
	)
	(footprint ""
		(layer "F.Cu")
		(at 25.146 -248.412 180)
		(property "Reference" "PR55"
			(at 0 0 180)
			(layer "F.SilkS")
			(hide yes)
			(effects
				(font
					(size 1.27 1.27)
				)
			)
		)
		(property "Value" "100KR2F-L1-GP"
			(at 0.064008 -3.993896 180)
			(unlocked yes)
			(layer "F.Fab")
			(hide yes)
			(effects
				(font
					(size 1.016 1.016)
					(thickness 0.1524)
				)
			)
		)
		(property "Device Type" "R402H16"
			(at 0.064008 -5.517896 180)
			(unlocked yes)
			(layer "F.Fab")
			(hide yes)
			(effects
				(font
					(size 1.016 1.016)
					(thickness 0.1524)
				)
			)
		)
		(duplicate_pad_numbers_are_jumpers no)
		(fp_line
			(start 0.508 -0.9398)
			(end -0.508 -0.9398)
			(stroke
				(width 0.1524)
				(type default)
			)
			(layer "F.SilkS")
		)
		(fp_line
			(start -0.508 -0.9398)
			(end -0.508 0.9398)
			(stroke
				(width 0.1524)
				(type default)
			)
			(layer "F.SilkS")
		)
		(fp_rect
			(start -0.508 0.9398)
			(end 0.508 -0.9398)
			(stroke
				(width 0)
				(type default)
			)
			(fill no)
			(layer "F.CrtYd")
		)
		(fp_rect
			(start -0.508 0.9398)
			(end 0.508 -0.9398)
			(stroke
				(width 0)
				(type default)
			)
			(fill no)
			(layer "F.Fab")
		)
		(pad "1" smd custom
			(at 0 -0.4445 180)
			(size 0.1397 0.1397)
			(layers "F.Cu" "F.Mask" "F.Paste")
			(net "P3V3_LX_REV")
			(options
				(clearance outline)
				(anchor circle)
			)
			(primitives
				(gr_poly
					(pts
						(arc
							(start -0.1778 -0.2794)
							(mid -0.249642 -0.249642)
							(end -0.2794 -0.1778)
						)
						(arc
							(start -0.2794 0.1778)
							(mid -0.249642 0.249642)
							(end -0.1778 0.2794)
						)
						(arc
							(start 0.1778 0.2794)
							(mid 0.249642 0.249642)
							(end 0.2794 0.1778)
						)
						(arc
							(start 0.2794 -0.1778)
							(mid 0.249642 -0.249642)
							(end 0.1778 -0.2794)
						)
					)
					(width 0)
					(fill yes)
				)
			)
		)
		(pad "2" smd custom
			(at 0 0.4445 180)
			(size 0.1397 0.1397)
			(layers "F.Cu" "F.Mask" "F.Paste")
			(net "P3V3_FB")
			(options
				(clearance outline)
				(anchor circle)
			)
			(primitives
				(gr_poly
					(pts
						(arc
							(start -0.1778 -0.2794)
							(mid -0.249642 -0.249642)
							(end -0.2794 -0.1778)
						)
						(arc
							(start -0.2794 0.1778)
							(mid -0.249642 0.249642)
							(end -0.1778 0.2794)
						)
						(arc
							(start 0.1778 0.2794)
							(mid 0.249642 0.249642)
							(end 0.2794 0.1778)
						)
						(arc
							(start 0.2794 -0.1778)
							(mid 0.249642 -0.249642)
							(end 0.1778 -0.2794)
						)
					)
					(width 0)
					(fill yes)
				)
			)
		)
	)
)
